(kicad_pcb
	(version 20260206)
	(generator "pcbnew")
	(generator_version "10.0")
	(general
		(thickness 1.6)
		(legacy_teardrops no)
	)
	(paper "A4")
	(title_block
		(title "03242023_DA0F0TMBIJ0_F0T_Motherboard_J_brd_V01_OCP.brd")
		(comment 1 "Grand Teton / footprints 3774-3779 of 6105")
	)
	(layers
		(0 "F.Cu" signal "TOP")
		(4 "In1.Cu" signal "GND")
		(6 "In2.Cu" signal "IN1")
		(8 "In3.Cu" signal "GND1")
		(10 "In4.Cu" signal "IN2")
		(12 "In5.Cu" signal "GND2")
		(14 "In6.Cu" signal "IN3")
		(16 "In7.Cu" signal "GND3")
		(18 "In8.Cu" signal "VCC")
		(20 "In9.Cu" signal "VCC1")
		(22 "In10.Cu" signal "GND4")
		(24 "In11.Cu" signal "IN4")
		(26 "In12.Cu" signal "GND5")
		(28 "In13.Cu" signal "IN5")
		(30 "In14.Cu" signal "GND6")
		(32 "In15.Cu" signal "IN6")
		(34 "In16.Cu" signal "GND7")
		(2 "B.Cu" signal "BOTTOM")
		(9 "F.Adhes" user "F.Adhesive")
		(11 "B.Adhes" user "B.Adhesive")
		(13 "F.Paste" user "Package Geometry/Pastemask Top")
		(15 "B.Paste" user "Package Geometry/Pastemask Bottom")
		(5 "F.SilkS" user "Ref Des/Silkscreen Top")
		(7 "B.SilkS" user "Ref Des/Silkscreen Bottom")
		(1 "F.Mask" user "Board Geometry/Soldermask Top")
		(3 "B.Mask" user "Board Geometry/Soldermask Bottom")
		(17 "Dwgs.User" user "User.Drawings")
		(19 "Cmts.User" user "User.Comments")
		(21 "Eco1.User" user "User.Eco1")
		(23 "Eco2.User" user "User.Eco2")
		(25 "Edge.Cuts" user "Board Geometry/Outline")
		(27 "Margin" user)
		(31 "F.CrtYd" user "Package Geometry/Place Bound Top")
		(29 "B.CrtYd" user "Package Geometry/Place Bound Bottom")
		(35 "F.Fab" user "Ref Des/Assembly Top")
		(33 "B.Fab" user "Ref Des/Assembly Bottom")
	)
	(footprint ""
		(layer "F.Cu")
		(at 44.29125 -181.983634)
		(property "Reference" "R330"
			(at 0 0 0)
			(layer "F.SilkS")
			(hide yes)
			(effects
				(font
					(size 1.27 1.27)
				)
			)
		)
		(property "Value" ""
			(at 0 0 0)
			(layer "F.Fab")
			(effects
				(font
					(size 1.27 1.27)
				)
			)
		)
		(duplicate_pad_numbers_are_jumpers no)
		(fp_line
			(start -2.044192 -0.94361)
			(end -2.044192 0.898398)
			(stroke
				(width 0.1524)
				(type default)
			)
			(layer "F.SilkS")
		)
		(fp_line
			(start -2.044192 0.94361)
			(end 2.044192 0.94361)
			(stroke
				(width 0.1524)
				(type default)
			)
			(layer "F.SilkS")
		)
		(fp_line
			(start 2.044192 -0.94361)
			(end -2.044192 -0.94361)
			(stroke
				(width 0.1524)
				(type default)
			)
			(layer "F.SilkS")
		)
		(fp_line
			(start 2.044192 0.94361)
			(end 2.044192 -0.94361)
			(stroke
				(width 0.1524)
				(type default)
			)
			(layer "F.SilkS")
		)
		(fp_line
			(start -1.625092 -0.87503)
			(end -1.625092 0.87503)
			(stroke
				(width 0.1)
				(type default)
			)
			(layer "F.Fab")
		)
		(fp_line
			(start -1.625092 0.87503)
			(end 1.625092 0.87503)
			(stroke
				(width 0.1)
				(type default)
			)
			(layer "F.Fab")
		)
		(fp_line
			(start 1.625092 -0.87503)
			(end -1.625092 -0.87503)
			(stroke
				(width 0.1)
				(type default)
			)
			(layer "F.Fab")
		)
		(fp_line
			(start 1.625092 0.87503)
			(end 1.625092 -0.87503)
			(stroke
				(width 0.1)
				(type default)
			)
			(layer "F.Fab")
		)
		(pad "1" smd rect
			(at -1.450086 0)
			(size 0.9144 1.6002)
			(layers "F.Cu" "F.Mask" "F.Paste")
			(net "PVNN_MAIN_CPU1")
		)
		(pad "2" smd rect
			(at 1.450086 0)
			(size 0.9144 1.6002)
			(layers "F.Cu" "F.Mask" "F.Paste")
			(net "PVNN_TERM_CPU1")
		)
	)
	(footprint ""
		(layer "F.Cu")
		(at 406.124664 -361.865926 180)
		(property "Reference" "R331"
			(at 0 0 180)
			(layer "F.SilkS")
			(hide yes)
			(effects
				(font
					(size 1.27 1.27)
				)
			)
		)
		(property "Value" ""
			(at 0 0 180)
			(layer "F.Fab")
			(effects
				(font
					(size 1.27 1.27)
				)
			)
		)
		(duplicate_pad_numbers_are_jumpers no)
		(fp_line
			(start 0.7874 0.4064)
			(end -0.7874 0.4064)
			(stroke
				(width 0.1524)
				(type default)
			)
			(layer "F.SilkS")
		)
		(fp_line
			(start 0.7874 -0.4064)
			(end 0.7874 0.4064)
			(stroke
				(width 0.1524)
				(type default)
			)
			(layer "F.SilkS")
		)
		(fp_line
			(start -0.7874 0.4064)
			(end -0.7874 -0.4064)
			(stroke
				(width 0.1524)
				(type default)
			)
			(layer "F.SilkS")
		)
		(fp_line
			(start -0.7874 -0.4064)
			(end 0.7874 -0.4064)
			(stroke
				(width 0.1524)
				(type default)
			)
			(layer "F.SilkS")
		)
		(fp_line
			(start 0.67945 0.3048)
			(end 0.120396 0.3048)
			(stroke
				(width 0.1)
				(type default)
			)
			(layer "F.Fab")
		)
		(fp_line
			(start 0.67945 -0.3048)
			(end 0.67945 0.3048)
			(stroke
				(width 0.1)
				(type default)
			)
			(layer "F.Fab")
		)
		(fp_line
			(start 0.12065 -0.2794)
			(end 0.12065 -0.3048)
			(stroke
				(width 0.1)
				(type default)
			)
			(layer "F.Fab")
		)
		(fp_line
			(start 0.12065 -0.3048)
			(end 0.67945 -0.3048)
			(stroke
				(width 0.1)
				(type default)
			)
			(layer "F.Fab")
		)
		(fp_line
			(start 0.120396 0.3048)
			(end 0.120396 0.2794)
			(stroke
				(width 0.1)
				(type default)
			)
			(layer "F.Fab")
		)
		(fp_line
			(start 0.120396 0.2794)
			(end -0.12065 0.2794)
			(stroke
				(width 0.1)
				(type default)
			)
			(layer "F.Fab")
		)
		(fp_line
			(start -0.12065 0.3048)
			(end -0.67945 0.3048)
			(stroke
				(width 0.1)
				(type default)
			)
			(layer "F.Fab")
		)
		(fp_line
			(start -0.12065 0.2794)
			(end -0.12065 0.3048)
			(stroke
				(width 0.1)
				(type default)
			)
			(layer "F.Fab")
		)
		(fp_line
			(start -0.12065 -0.2794)
			(end 0.12065 -0.2794)
			(stroke
				(width 0.1)
				(type default)
			)
			(layer "F.Fab")
		)
		(fp_line
			(start -0.12065 -0.305054)
			(end -0.12065 -0.2794)
			(stroke
				(width 0.1)
				(type default)
			)
			(layer "F.Fab")
		)
		(fp_line
			(start -0.67945 0.3048)
			(end -0.67945 -0.305054)
			(stroke
				(width 0.1)
				(type default)
			)
			(layer "F.Fab")
		)
		(fp_line
			(start -0.67945 -0.305054)
			(end -0.12065 -0.305054)
			(stroke
				(width 0.1)
				(type default)
			)
			(layer "F.Fab")
		)
		(pad "1" smd circle
			(at -0.40005 0 180)
			(size 0 0)
			(layers "F.Cu" "F.Mask" "F.Paste")
			(net "P3V3_AUX")
		)
		(pad "2" smd circle
			(at 0.40005 0 180)
			(size 0 0)
			(layers "F.Cu" "F.Mask" "F.Paste")
			(net "PD_PIROM_CPU0_ADDR2")
		)
	)
	(footprint ""
		(layer "F.Cu")
		(at 352.264726 -260.364986 -90)
		(property "Reference" "C406"
			(at 0 0 270)
			(layer "F.SilkS")
			(hide yes)
			(effects
				(font
					(size 1.27 1.27)
				)
			)
		)
		(property "Value" ""
			(at 0 0 270)
			(layer "F.Fab")
			(effects
				(font
					(size 1.27 1.27)
				)
			)
		)
		(duplicate_pad_numbers_are_jumpers no)
		(fp_line
			(start -0.7874 0.4064)
			(end -0.7874 -0.4064)
			(stroke
				(width 0.1524)
				(type default)
			)
			(layer "F.SilkS")
		)
		(fp_line
			(start 0.7874 0.4064)
			(end -0.7874 0.4064)
			(stroke
				(width 0.1524)
				(type default)
			)
			(layer "F.SilkS")
		)
		(fp_line
			(start -0.7874 -0.4064)
			(end 0.7874 -0.4064)
			(stroke
				(width 0.1524)
				(type default)
			)
			(layer "F.SilkS")
		)
		(fp_line
			(start 0.7874 -0.4064)
			(end 0.7874 0.4064)
			(stroke
				(width 0.1524)
				(type default)
			)
			(layer "F.SilkS")
		)
		(fp_line
			(start -0.67945 0.3048)
			(end -0.67945 -0.305054)
			(stroke
				(width 0.1)
				(type default)
			)
			(layer "F.Fab")
		)
		(fp_line
			(start -0.12065 0.3048)
			(end -0.67945 0.3048)
			(stroke
				(width 0.1)
				(type default)
			)
			(layer "F.Fab")
		)
		(fp_line
			(start 0.120396 0.3048)
			(end 0.120396 0.2794)
			(stroke
				(width 0.1)
				(type default)
			)
			(layer "F.Fab")
		)
		(fp_line
			(start 0.67945 0.3048)
			(end 0.120396 0.3048)
			(stroke
				(width 0.1)
				(type default)
			)
			(layer "F.Fab")
		)
		(fp_line
			(start -0.12065 0.2794)
			(end -0.12065 0.3048)
			(stroke
				(width 0.1)
				(type default)
			)
			(layer "F.Fab")
		)
		(fp_line
			(start 0.120396 0.2794)
			(end -0.12065 0.2794)
			(stroke
				(width 0.1)
				(type default)
			)
			(layer "F.Fab")
		)
		(fp_line
			(start -0.12065 -0.2794)
			(end 0.12065 -0.2794)
			(stroke
				(width 0.1)
				(type default)
			)
			(layer "F.Fab")
		)
		(fp_line
			(start 0.12065 -0.2794)
			(end 0.12065 -0.3048)
			(stroke
				(width 0.1)
				(type default)
			)
			(layer "F.Fab")
		)
		(fp_line
			(start 0.12065 -0.3048)
			(end 0.67945 -0.3048)
			(stroke
				(width 0.1)
				(type default)
			)
			(layer "F.Fab")
		)
		(fp_line
			(start 0.67945 -0.3048)
			(end 0.67945 0.3048)
			(stroke
				(width 0.1)
				(type default)
			)
			(layer "F.Fab")
		)
		(fp_line
			(start -0.67945 -0.305054)
			(end -0.12065 -0.305054)
			(stroke
				(width 0.1)
				(type default)
			)
			(layer "F.Fab")
		)
		(fp_line
			(start -0.12065 -0.305054)
			(end -0.12065 -0.2794)
			(stroke
				(width 0.1)
				(type default)
			)
			(layer "F.Fab")
		)
		(pad "1" smd circle
			(at -0.40005 0 270)
			(size 0 0)
			(layers "F.Cu" "F.Mask" "F.Paste")
			(net "PVCCFA_EHV_FIVRA_CPU0")
		)
		(pad "2" smd circle
			(at 0.40005 0 270)
			(size 0 0)
			(layers "F.Cu" "F.Mask" "F.Paste")
			(net "GND")
		)
	)
	(footprint ""
		(layer "F.Cu")
		(at 345.002358 -354.98913 -90)
		(property "Reference" "PC1652"
			(at 0 0 270)
			(layer "F.SilkS")
			(hide yes)
			(effects
				(font
					(size 1.27 1.27)
				)
			)
		)
		(property "Value" ""
			(at 0 0 270)
			(layer "F.Fab")
			(effects
				(font
					(size 1.27 1.27)
				)
			)
		)
		(duplicate_pad_numbers_are_jumpers no)
		(fp_line
			(start -0.7874 0.4064)
			(end -0.7874 -0.4064)
			(stroke
				(width 0.1524)
				(type default)
			)
			(layer "F.SilkS")
		)
		(fp_line
			(start 0.7874 0.4064)
			(end -0.7874 0.4064)
			(stroke
				(width 0.1524)
				(type default)
			)
			(layer "F.SilkS")
		)
		(fp_line
			(start -0.7874 -0.4064)
			(end 0.7874 -0.4064)
			(stroke
				(width 0.1524)
				(type default)
			)
			(layer "F.SilkS")
		)
		(fp_line
			(start 0.7874 -0.4064)
			(end 0.7874 0.4064)
			(stroke
				(width 0.1524)
				(type default)
			)
			(layer "F.SilkS")
		)
		(fp_line
			(start -0.67945 0.3048)
			(end -0.67945 -0.305054)
			(stroke
				(width 0.1)
				(type default)
			)
			(layer "F.Fab")
		)
		(fp_line
			(start -0.12065 0.3048)
			(end -0.67945 0.3048)
			(stroke
				(width 0.1)
				(type default)
			)
			(layer "F.Fab")
		)
		(fp_line
			(start 0.120396 0.3048)
			(end 0.120396 0.2794)
			(stroke
				(width 0.1)
				(type default)
			)
			(layer "F.Fab")
		)
		(fp_line
			(start 0.67945 0.3048)
			(end 0.120396 0.3048)
			(stroke
				(width 0.1)
				(type default)
			)
			(layer "F.Fab")
		)
		(fp_line
			(start -0.12065 0.2794)
			(end -0.12065 0.3048)
			(stroke
				(width 0.1)
				(type default)
			)
			(layer "F.Fab")
		)
		(fp_line
			(start 0.120396 0.2794)
			(end -0.12065 0.2794)
			(stroke
				(width 0.1)
				(type default)
			)
			(layer "F.Fab")
		)
		(fp_line
			(start -0.12065 -0.2794)
			(end 0.12065 -0.2794)
			(stroke
				(width 0.1)
				(type default)
			)
			(layer "F.Fab")
		)
		(fp_line
			(start 0.12065 -0.2794)
			(end 0.12065 -0.3048)
			(stroke
				(width 0.1)
				(type default)
			)
			(layer "F.Fab")
		)
		(fp_line
			(start 0.12065 -0.3048)
			(end 0.67945 -0.3048)
			(stroke
				(width 0.1)
				(type default)
			)
			(layer "F.Fab")
		)
		(fp_line
			(start 0.67945 -0.3048)
			(end 0.67945 0.3048)
			(stroke
				(width 0.1)
				(type default)
			)
			(layer "F.Fab")
		)
		(fp_line
			(start -0.67945 -0.305054)
			(end -0.12065 -0.305054)
			(stroke
				(width 0.1)
				(type default)
			)
			(layer "F.Fab")
		)
		(fp_line
			(start -0.12065 -0.305054)
			(end -0.12065 -0.2794)
			(stroke
				(width 0.1)
				(type default)
			)
			(layer "F.Fab")
		)
		(pad "1" smd circle
			(at -0.40005 0 270)
			(size 0 0)
			(layers "F.Cu" "F.Mask" "F.Paste")
			(net "P12V_AUX")
		)
		(pad "2" smd circle
			(at 0.40005 0 270)
			(size 0 0)
			(layers "F.Cu" "F.Mask" "F.Paste")
			(net "GND")
		)
	)
	(footprint ""
		(layer "F.Cu")
		(at 194.856608 -404.086822 180)
		(property "Reference" "PC2184"
			(at 0 0 180)
			(layer "F.SilkS")
			(hide yes)
			(effects
				(font
					(size 1.27 1.27)
				)
			)
		)
		(property "Value" ""
			(at 0 0 180)
			(layer "F.Fab")
			(effects
				(font
					(size 1.27 1.27)
				)
			)
		)
		(duplicate_pad_numbers_are_jumpers no)
		(fp_line
			(start 0.7874 0.4064)
			(end -0.7874 0.4064)
			(stroke
				(width 0.1524)
				(type default)
			)
			(layer "F.SilkS")
		)
		(fp_line
			(start 0.7874 -0.4064)
			(end 0.7874 0.4064)
			(stroke
				(width 0.1524)
				(type default)
			)
			(layer "F.SilkS")
		)
		(fp_line
			(start -0.7874 0.4064)
			(end -0.7874 -0.4064)
			(stroke
				(width 0.1524)
				(type default)
			)
			(layer "F.SilkS")
		)
		(fp_line
			(start -0.7874 -0.4064)
			(end 0.7874 -0.4064)
			(stroke
				(width 0.1524)
				(type default)
			)
			(layer "F.SilkS")
		)
		(fp_line
			(start 0.67945 0.3048)
			(end 0.120396 0.3048)
			(stroke
				(width 0.1)
				(type default)
			)
			(layer "F.Fab")
		)
		(fp_line
			(start 0.67945 -0.3048)
			(end 0.67945 0.3048)
			(stroke
				(width 0.1)
				(type default)
			)
			(layer "F.Fab")
		)
		(fp_line
			(start 0.12065 -0.2794)
			(end 0.12065 -0.3048)
			(stroke
				(width 0.1)
				(type default)
			)
			(layer "F.Fab")
		)
		(fp_line
			(start 0.12065 -0.3048)
			(end 0.67945 -0.3048)
			(stroke
				(width 0.1)
				(type default)
			)
			(layer "F.Fab")
		)
		(fp_line
			(start 0.120396 0.3048)
			(end 0.120396 0.2794)
			(stroke
				(width 0.1)
				(type default)
			)
			(layer "F.Fab")
		)
		(fp_line
			(start 0.120396 0.2794)
			(end -0.12065 0.2794)
			(stroke
				(width 0.1)
				(type default)
			)
			(layer "F.Fab")
		)
		(fp_line
			(start -0.12065 0.3048)
			(end -0.67945 0.3048)
			(stroke
				(width 0.1)
				(type default)
			)
			(layer "F.Fab")
		)
		(fp_line
			(start -0.12065 0.2794)
			(end -0.12065 0.3048)
			(stroke
				(width 0.1)
				(type default)
			)
			(layer "F.Fab")
		)
		(fp_line
			(start -0.12065 -0.2794)
			(end 0.12065 -0.2794)
			(stroke
				(width 0.1)
				(type default)
			)
			(layer "F.Fab")
		)
		(fp_line
			(start -0.12065 -0.305054)
			(end -0.12065 -0.2794)
			(stroke
				(width 0.1)
				(type default)
			)
			(layer "F.Fab")
		)
		(fp_line
			(start -0.67945 0.3048)
			(end -0.67945 -0.305054)
			(stroke
				(width 0.1)
				(type default)
			)
			(layer "F.Fab")
		)
		(fp_line
			(start -0.67945 -0.305054)
			(end -0.12065 -0.305054)
			(stroke
				(width 0.1)
				(type default)
			)
			(layer "F.Fab")
		)
		(pad "1" smd circle
			(at -0.40005 0 180)
			(size 0 0)
			(layers "F.Cu" "F.Mask" "F.Paste")
			(net "HSC_SS")
		)
		(pad "2" smd circle
			(at 0.40005 0 180)
			(size 0 0)
			(layers "F.Cu" "F.Mask" "F.Paste")
			(net "AGND_HSC")
		)
	)
	(footprint ""
		(layer "F.Cu")
		(at 205.397608 -405.839422 180)
		(property "Reference" "PC2185"
			(at 0 0 180)
			(layer "F.SilkS")
			(hide yes)
			(effects
				(font
					(size 1.27 1.27)
				)
			)
		)
		(property "Value" ""
			(at 0 0 180)
			(layer "F.Fab")
			(effects
				(font
					(size 1.27 1.27)
				)
			)
		)
		(duplicate_pad_numbers_are_jumpers no)
		(fp_line
			(start 0.7874 0.4064)
			(end -0.7874 0.4064)
			(stroke
				(width 0.1524)
				(type default)
			)
			(layer "F.SilkS")
		)
		(fp_line
			(start 0.7874 -0.4064)
			(end 0.7874 0.4064)
			(stroke
				(width 0.1524)
				(type default)
			)
			(layer "F.SilkS")
		)
		(fp_line
			(start -0.7874 0.4064)
			(end -0.7874 -0.4064)
			(stroke
				(width 0.1524)
				(type default)
			)
			(layer "F.SilkS")
		)
		(fp_line
			(start -0.7874 -0.4064)
			(end 0.7874 -0.4064)
			(stroke
				(width 0.1524)
				(type default)
			)
			(layer "F.SilkS")
		)
		(fp_line
			(start 0.67945 0.3048)
			(end 0.120396 0.3048)
			(stroke
				(width 0.1)
				(type default)
			)
			(layer "F.Fab")
		)
		(fp_line
			(start 0.67945 -0.3048)
			(end 0.67945 0.3048)
			(stroke
				(width 0.1)
				(type default)
			)
			(layer "F.Fab")
		)
		(fp_line
			(start 0.12065 -0.2794)
			(end 0.12065 -0.3048)
			(stroke
				(width 0.1)
				(type default)
			)
			(layer "F.Fab")
		)
		(fp_line
			(start 0.12065 -0.3048)
			(end 0.67945 -0.3048)
			(stroke
				(width 0.1)
				(type default)
			)
			(layer "F.Fab")
		)
		(fp_line
			(start 0.120396 0.3048)
			(end 0.120396 0.2794)
			(stroke
				(width 0.1)
				(type default)
			)
			(layer "F.Fab")
		)
		(fp_line
			(start 0.120396 0.2794)
			(end -0.12065 0.2794)
			(stroke
				(width 0.1)
				(type default)
			)
			(layer "F.Fab")
		)
		(fp_line
			(start -0.12065 0.3048)
			(end -0.67945 0.3048)
			(stroke
				(width 0.1)
				(type default)
			)
			(layer "F.Fab")
		)
		(fp_line
			(start -0.12065 0.2794)
			(end -0.12065 0.3048)
			(stroke
				(width 0.1)
				(type default)
			)
			(layer "F.Fab")
		)
		(fp_line
			(start -0.12065 -0.2794)
			(end 0.12065 -0.2794)
			(stroke
				(width 0.1)
				(type default)
			)
			(layer "F.Fab")
		)
		(fp_line
			(start -0.12065 -0.305054)
			(end -0.12065 -0.2794)
			(stroke
				(width 0.1)
				(type default)
			)
			(layer "F.Fab")
		)
		(fp_line
			(start -0.67945 0.3048)
			(end -0.67945 -0.305054)
			(stroke
				(width 0.1)
				(type default)
			)
			(layer "F.Fab")
		)
		(fp_line
			(start -0.67945 -0.305054)
			(end -0.12065 -0.305054)
			(stroke
				(width 0.1)
				(type default)
			)
			(layer "F.Fab")
		)
		(pad "1" smd circle
			(at -0.40005 0 180)
			(size 0 0)
			(layers "F.Cu" "F.Mask" "F.Paste")
			(net "HSC_SS")
		)
		(pad "2" smd circle
			(at 0.40005 0 180)
			(size 0 0)
			(layers "F.Cu" "F.Mask" "F.Paste")
			(net "AGND_HSC")
		)
	)
)
